(kicad_pcb
	(version 20260206)
	(generator "pcbnew")
	(generator_version "10.0")
	(general
		(thickness 1.6)
		(legacy_teardrops no)
	)
	(paper "A4")
	(title_block
		(title "Bryce Canyon_IOM_M2_16342-2_OCP.brd")
		(comment 1 "Bryce Canyon / footprints 371-377 of 1146")
	)
	(layers
		(0 "F.Cu" signal "TOP")
		(4 "In1.Cu" signal "L2GND")
		(6 "In2.Cu" signal "L3")
		(8 "In3.Cu" signal "L4VCC")
		(10 "In4.Cu" signal "L5VCC")
		(12 "In5.Cu" signal "L6")
		(14 "In6.Cu" signal "L7GND")
		(2 "B.Cu" signal "BOTTOM")
		(9 "F.Adhes" user "F.Adhesive")
		(11 "B.Adhes" user "B.Adhesive")
		(13 "F.Paste" user "Package Geometry/Pastemask Top")
		(15 "B.Paste" user "Package Geometry/Pastemask Bottom")
		(5 "F.SilkS" user "Ref Des/Silkscreen Top")
		(7 "B.SilkS" user "Ref Des/Silkscreen Bottom")
		(1 "F.Mask" user "Board Geometry/Soldermask Top")
		(3 "B.Mask" user "Board Geometry/Soldermask Bottom")
		(17 "Dwgs.User" user "User.Drawings")
		(19 "Cmts.User" user "User.Comments")
		(21 "Eco1.User" user "User.Eco1")
		(23 "Eco2.User" user "User.Eco2")
		(25 "Edge.Cuts" user "Board Geometry/Outline")
		(27 "Margin" user)
		(31 "F.CrtYd" user "Package Geometry/Place Bound Top")
		(29 "B.CrtYd" user "Package Geometry/Place Bound Bottom")
		(35 "F.Fab" user "Ref Des/Assembly Top")
		(33 "B.Fab" user "Ref Des/Assembly Bottom")
	)
	(footprint ""
		(layer "F.Cu")
		(at 124.9426 -8.636 90)
		(property "Reference" "R435"
			(at 0 0 90)
			(layer "F.SilkS")
			(hide yes)
			(effects
				(font
					(size 1.27 1.27)
				)
			)
		)
		(property "Value" "26K1R2F-2-GP"
			(at 0.064008 -3.993896 90)
			(unlocked yes)
			(layer "F.Fab")
			(hide yes)
			(effects
				(font
					(size 1.016 1.016)
					(thickness 0.1524)
				)
			)
		)
		(property "Device Type" "R402H16"
			(at 0.064008 -5.517896 90)
			(unlocked yes)
			(layer "F.Fab")
			(hide yes)
			(effects
				(font
					(size 1.016 1.016)
					(thickness 0.1524)
				)
			)
		)
		(duplicate_pad_numbers_are_jumpers no)
		(fp_line
			(start 0.508 -0.9398)
			(end -0.508 -0.9398)
			(stroke
				(width 0.1524)
				(type default)
			)
			(layer "F.SilkS")
		)
		(fp_line
			(start -0.508 -0.9398)
			(end -0.508 0.9398)
			(stroke
				(width 0.1524)
				(type default)
			)
			(layer "F.SilkS")
		)
		(fp_rect
			(start -0.508 0.9398)
			(end 0.508 -0.9398)
			(stroke
				(width 0)
				(type default)
			)
			(fill no)
			(layer "F.CrtYd")
		)
		(fp_rect
			(start -0.508 0.9398)
			(end 0.508 -0.9398)
			(stroke
				(width 0)
				(type default)
			)
			(fill no)
			(layer "F.Fab")
		)
		(pad "1" smd custom
			(at 0 -0.4445 90)
			(size 0.1397 0.1397)
			(layers "F.Cu" "F.Mask" "F.Paste")
			(net "P12V_IOM_PGOOD")
			(options
				(clearance outline)
				(anchor circle)
			)
			(primitives
				(gr_poly
					(pts
						(arc
							(start -0.1778 -0.2794)
							(mid -0.249642 -0.249642)
							(end -0.2794 -0.1778)
						)
						(arc
							(start -0.2794 0.1778)
							(mid -0.249642 0.249642)
							(end -0.1778 0.2794)
						)
						(arc
							(start 0.1778 0.2794)
							(mid 0.249642 0.249642)
							(end 0.2794 0.1778)
						)
						(arc
							(start 0.2794 -0.1778)
							(mid 0.249642 -0.249642)
							(end 0.1778 -0.2794)
						)
					)
					(width 0)
					(fill yes)
				)
			)
		)
		(pad "2" smd custom
			(at 0 0.4445 90)
			(size 0.1397 0.1397)
			(layers "F.Cu" "F.Mask" "F.Paste")
			(net "GND")
			(options
				(clearance outline)
				(anchor circle)
			)
			(primitives
				(gr_poly
					(pts
						(arc
							(start -0.1778 -0.2794)
							(mid -0.249642 -0.249642)
							(end -0.2794 -0.1778)
						)
						(arc
							(start -0.2794 0.1778)
							(mid -0.249642 0.249642)
							(end -0.1778 0.2794)
						)
						(arc
							(start 0.1778 0.2794)
							(mid 0.249642 0.249642)
							(end 0.2794 0.1778)
						)
						(arc
							(start 0.2794 -0.1778)
							(mid 0.249642 -0.249642)
							(end 0.1778 -0.2794)
						)
					)
					(width 0)
					(fill yes)
				)
			)
		)
	)
	(footprint ""
		(layer "F.Cu")
		(at 57.3786 -158.8516)
		(property "Reference" "R390"
			(at 0 0 0)
			(layer "F.SilkS")
			(hide yes)
			(effects
				(font
					(size 1.27 1.27)
				)
			)
		)
		(property "Value" "4K7R2F-GP"
			(at 0.064008 -3.993896 0)
			(unlocked yes)
			(layer "F.Fab")
			(hide yes)
			(effects
				(font
					(size 1.016 1.016)
					(thickness 0.1524)
				)
			)
		)
		(property "Device Type" "R402H16"
			(at 0.064008 -5.517896 0)
			(unlocked yes)
			(layer "F.Fab")
			(hide yes)
			(effects
				(font
					(size 1.016 1.016)
					(thickness 0.1524)
				)
			)
		)
		(duplicate_pad_numbers_are_jumpers no)
		(fp_line
			(start -0.508 -0.9398)
			(end -0.508 0.9398)
			(stroke
				(width 0.1524)
				(type default)
			)
			(layer "F.SilkS")
		)
		(fp_line
			(start 0.508 -0.9398)
			(end -0.508 -0.9398)
			(stroke
				(width 0.1524)
				(type default)
			)
			(layer "F.SilkS")
		)
		(fp_rect
			(start -0.508 0.9398)
			(end 0.508 -0.9398)
			(stroke
				(width 0)
				(type default)
			)
			(fill no)
			(layer "F.CrtYd")
		)
		(fp_rect
			(start -0.508 0.9398)
			(end 0.508 -0.9398)
			(stroke
				(width 0)
				(type default)
			)
			(fill no)
			(layer "F.Fab")
		)
		(pad "1" smd custom
			(at 0 -0.4445)
			(size 0.1397 0.1397)
			(layers "F.Cu" "F.Mask" "F.Paste")
			(net "P3V3_STBY")
			(options
				(clearance outline)
				(anchor circle)
			)
			(primitives
				(gr_poly
					(pts
						(arc
							(start -0.1778 -0.2794)
							(mid -0.249642 -0.249642)
							(end -0.2794 -0.1778)
						)
						(arc
							(start -0.2794 0.1778)
							(mid -0.249642 0.249642)
							(end -0.1778 0.2794)
						)
						(arc
							(start 0.1778 0.2794)
							(mid 0.249642 0.249642)
							(end 0.2794 0.1778)
						)
						(arc
							(start 0.2794 -0.1778)
							(mid 0.249642 -0.249642)
							(end 0.1778 -0.2794)
						)
					)
					(width 0)
					(fill yes)
				)
			)
		)
		(pad "2" smd custom
			(at 0 0.4445)
			(size 0.1397 0.1397)
			(layers "F.Cu" "F.Mask" "F.Paste")
			(net "MAC2_TXCTL")
			(options
				(clearance outline)
				(anchor circle)
			)
			(primitives
				(gr_poly
					(pts
						(arc
							(start -0.1778 -0.2794)
							(mid -0.249642 -0.249642)
							(end -0.2794 -0.1778)
						)
						(arc
							(start -0.2794 0.1778)
							(mid -0.249642 0.249642)
							(end -0.1778 0.2794)
						)
						(arc
							(start 0.1778 0.2794)
							(mid 0.249642 0.249642)
							(end 0.2794 0.1778)
						)
						(arc
							(start 0.2794 -0.1778)
							(mid 0.249642 -0.249642)
							(end 0.1778 -0.2794)
						)
					)
					(width 0)
					(fill yes)
				)
			)
		)
	)
	(footprint ""
		(layer "F.Cu")
		(at 63.7032 -172.1104 180)
		(property "Reference" "R71"
			(at 0 0 180)
			(layer "F.SilkS")
			(hide yes)
			(effects
				(font
					(size 1.27 1.27)
				)
			)
		)
		(property "Value" "4K75R2F-1-GP"
			(at 0.064008 -3.993896 180)
			(unlocked yes)
			(layer "F.Fab")
			(hide yes)
			(effects
				(font
					(size 1.016 1.016)
					(thickness 0.1524)
				)
			)
		)
		(property "Device Type" "R402H16"
			(at 0.064008 -5.517896 180)
			(unlocked yes)
			(layer "F.Fab")
			(hide yes)
			(effects
				(font
					(size 1.016 1.016)
					(thickness 0.1524)
				)
			)
		)
		(duplicate_pad_numbers_are_jumpers no)
		(fp_line
			(start 0.508 -0.9398)
			(end -0.508 -0.9398)
			(stroke
				(width 0.1524)
				(type default)
			)
			(layer "F.SilkS")
		)
		(fp_line
			(start -0.508 -0.9398)
			(end -0.508 0.9398)
			(stroke
				(width 0.1524)
				(type default)
			)
			(layer "F.SilkS")
		)
		(fp_rect
			(start -0.508 0.9398)
			(end 0.508 -0.9398)
			(stroke
				(width 0)
				(type default)
			)
			(fill no)
			(layer "F.CrtYd")
		)
		(fp_rect
			(start -0.508 0.9398)
			(end 0.508 -0.9398)
			(stroke
				(width 0)
				(type default)
			)
			(fill no)
			(layer "F.Fab")
		)
		(pad "1" smd custom
			(at 0 -0.4445 180)
			(size 0.1397 0.1397)
			(layers "F.Cu" "F.Mask" "F.Paste")
			(net "P3V3_STBY")
			(options
				(clearance outline)
				(anchor circle)
			)
			(primitives
				(gr_poly
					(pts
						(arc
							(start -0.1778 -0.2794)
							(mid -0.249642 -0.249642)
							(end -0.2794 -0.1778)
						)
						(arc
							(start -0.2794 0.1778)
							(mid -0.249642 0.249642)
							(end -0.1778 0.2794)
						)
						(arc
							(start 0.1778 0.2794)
							(mid 0.249642 0.249642)
							(end 0.2794 0.1778)
						)
						(arc
							(start 0.2794 -0.1778)
							(mid 0.249642 -0.249642)
							(end 0.1778 -0.2794)
						)
					)
					(width 0)
					(fill yes)
				)
			)
		)
		(pad "2" smd custom
			(at 0 0.4445 180)
			(size 0.1397 0.1397)
			(layers "F.Cu" "F.Mask" "F.Paste")
			(net "FM_TPM_PRSNT_RST_N_C")
			(options
				(clearance outline)
				(anchor circle)
			)
			(primitives
				(gr_poly
					(pts
						(arc
							(start -0.1778 -0.2794)
							(mid -0.249642 -0.249642)
							(end -0.2794 -0.1778)
						)
						(arc
							(start -0.2794 0.1778)
							(mid -0.249642 0.249642)
							(end -0.1778 0.2794)
						)
						(arc
							(start 0.1778 0.2794)
							(mid 0.249642 0.249642)
							(end 0.2794 0.1778)
						)
						(arc
							(start 0.2794 -0.1778)
							(mid 0.249642 -0.249642)
							(end 0.1778 -0.2794)
						)
					)
					(width 0)
					(fill yes)
				)
			)
		)
	)
	(footprint ""
		(layer "F.Cu")
		(at 183.1594 -111.0234 180)
		(property "Reference" "R552"
			(at 0 0 180)
			(layer "F.SilkS")
			(hide yes)
			(effects
				(font
					(size 1.27 1.27)
				)
			)
		)
		(property "Value" "4K7R2F-GP"
			(at 0.064008 -3.993896 180)
			(unlocked yes)
			(layer "F.Fab")
			(hide yes)
			(effects
				(font
					(size 1.016 1.016)
					(thickness 0.1524)
				)
			)
		)
		(property "Device Type" "R402H16"
			(at 0.064008 -5.517896 180)
			(unlocked yes)
			(layer "F.Fab")
			(hide yes)
			(effects
				(font
					(size 1.016 1.016)
					(thickness 0.1524)
				)
			)
		)
		(duplicate_pad_numbers_are_jumpers no)
		(fp_line
			(start 0.508 -0.9398)
			(end -0.508 -0.9398)
			(stroke
				(width 0.1524)
				(type default)
			)
			(layer "F.SilkS")
		)
		(fp_line
			(start -0.508 -0.9398)
			(end -0.508 0.9398)
			(stroke
				(width 0.1524)
				(type default)
			)
			(layer "F.SilkS")
		)
		(fp_rect
			(start -0.508 0.9398)
			(end 0.508 -0.9398)
			(stroke
				(width 0)
				(type default)
			)
			(fill no)
			(layer "F.CrtYd")
		)
		(fp_rect
			(start -0.508 0.9398)
			(end 0.508 -0.9398)
			(stroke
				(width 0)
				(type default)
			)
			(fill no)
			(layer "F.Fab")
		)
		(pad "1" smd custom
			(at 0 -0.4445 180)
			(size 0.1397 0.1397)
			(layers "F.Cu" "F.Mask" "F.Paste")
			(net "TEMP_1_A1")
			(options
				(clearance outline)
				(anchor circle)
			)
			(primitives
				(gr_poly
					(pts
						(arc
							(start -0.1778 -0.2794)
							(mid -0.249642 -0.249642)
							(end -0.2794 -0.1778)
						)
						(arc
							(start -0.2794 0.1778)
							(mid -0.249642 0.249642)
							(end -0.1778 0.2794)
						)
						(arc
							(start 0.1778 0.2794)
							(mid 0.249642 0.249642)
							(end 0.2794 0.1778)
						)
						(arc
							(start 0.2794 -0.1778)
							(mid 0.249642 -0.249642)
							(end 0.1778 -0.2794)
						)
					)
					(width 0)
					(fill yes)
				)
			)
		)
		(pad "2" smd custom
			(at 0 0.4445 180)
			(size 0.1397 0.1397)
			(layers "F.Cu" "F.Mask" "F.Paste")
			(net "GND")
			(options
				(clearance outline)
				(anchor circle)
			)
			(primitives
				(gr_poly
					(pts
						(arc
							(start -0.1778 -0.2794)
							(mid -0.249642 -0.249642)
							(end -0.2794 -0.1778)
						)
						(arc
							(start -0.2794 0.1778)
							(mid -0.249642 0.249642)
							(end -0.1778 0.2794)
						)
						(arc
							(start 0.1778 0.2794)
							(mid 0.249642 0.249642)
							(end 0.2794 0.1778)
						)
						(arc
							(start 0.2794 -0.1778)
							(mid 0.249642 -0.249642)
							(end 0.1778 -0.2794)
						)
					)
					(width 0)
					(fill yes)
				)
			)
		)
	)
	(footprint ""
		(layer "F.Cu")
		(at 203.503276 -105.12425)
		(property "Reference" "U85"
			(at 0 0 0)
			(layer "F.SilkS")
			(hide yes)
			(effects
				(font
					(size 1.27 1.27)
				)
			)
		)
		(property "Value" "TMP75AIDGKR-GP"
			(at -0.1143 -9.1948 0)
			(unlocked yes)
			(layer "F.Fab")
			(hide yes)
			(effects
				(font
					(size 1.016 1.016)
					(thickness 0.1524)
				)
			)
		)
		(property "Device Type" "MSOP8-1H44"
			(at -0.1143 -10.795 0)
			(unlocked yes)
			(layer "F.Fab")
			(hide yes)
			(effects
				(font
					(size 1.016 1.016)
					(thickness 0.1524)
				)
			)
		)
		(duplicate_pad_numbers_are_jumpers no)
		(fp_line
			(start -1.9558 -1.016)
			(end -1.9558 1.016)
			(stroke
				(width 0.1524)
				(type default)
			)
			(layer "F.SilkS")
		)
		(fp_line
			(start -1.9558 -0.5461)
			(end -1.4478 -0.0381)
			(stroke
				(width 0.1524)
				(type default)
			)
			(layer "F.SilkS")
		)
		(fp_line
			(start -1.9558 1.016)
			(end 1.0795 1.016)
			(stroke
				(width 0.1524)
				(type default)
			)
			(layer "F.SilkS")
		)
		(fp_line
			(start -1.778 1.0922)
			(end -1.778 3.048)
			(stroke
				(width 0.508)
				(type default)
			)
			(layer "F.SilkS")
		)
		(fp_line
			(start -1.4478 -0.0381)
			(end -1.9558 0.4699)
			(stroke
				(width 0.1524)
				(type default)
			)
			(layer "F.SilkS")
		)
		(fp_line
			(start 1.0795 -1.016)
			(end -1.9558 -1.016)
			(stroke
				(width 0.1524)
				(type default)
			)
			(layer "F.SilkS")
		)
		(fp_line
			(start 1.0795 1.016)
			(end 1.0795 -1.016)
			(stroke
				(width 0.1524)
				(type default)
			)
			(layer "F.SilkS")
		)
		(fp_poly
			(pts
				(xy -1.1557 -1.016) (xy -1.1557 1.016) (xy 1.1557 1.016) (xy 1.1557 -1.016)
			)
			(stroke
				(width 0)
				(type default)
			)
			(fill yes)
			(layer "F.SilkS")
		)
		(fp_rect
			(start -1.4986 2.4511)
			(end 1.4986 -2.4511)
			(stroke
				(width 0)
				(type default)
			)
			(fill no)
			(layer "F.CrtYd")
		)
		(fp_poly
			(pts
				(xy -2.032 3.302) (xy -2.032 -3.302) (xy 2.032 -3.302) (xy 2.032 -2.1209) (xy 1.4986 -2.1209) (xy 1.4986 -2.4511)
				(xy -1.4986 -2.4511) (xy -1.4986 2.4511) (xy 1.4986 2.4511) (xy 1.4986 -2.1082) (xy 2.032 -2.1082)
				(xy 2.032 3.302)
			)
			(stroke
				(width 0)
				(type default)
			)
			(fill no)
			(layer "F.CrtYd")
		)
		(fp_rect
			(start -2.032 3.302)
			(end 2.032 -3.302)
			(stroke
				(width 0)
				(type default)
			)
			(fill no)
			(layer "F.Fab")
		)
		(pad "1" smd rect
			(at -0.97536 2.05486)
			(size 0.3556 1.524)
			(layers "F.Cu" "F.Mask" "F.Paste")
			(net "TEMP_2_SDA")
		)
		(pad "2" smd rect
			(at -0.32512 2.05486)
			(size 0.3556 1.524)
			(layers "F.Cu" "F.Mask" "F.Paste")
			(net "TEMP_2_SCL")
		)
		(pad "3" smd rect
			(at 0.32512 2.05486)
			(size 0.3556 1.524)
			(layers "F.Cu" "F.Mask" "F.Paste")
			(net "TEMP_2_ALERT")
		)
		(pad "4" smd rect
			(at 0.97536 2.05486)
			(size 0.3556 1.524)
			(layers "F.Cu" "F.Mask" "F.Paste")
			(net "GND")
		)
		(pad "5" smd rect
			(at 0.97536 -2.05486)
			(size 0.3556 1.524)
			(layers "F.Cu" "F.Mask" "F.Paste")
			(net "TEMP_2_A2")
		)
		(pad "6" smd rect
			(at 0.32512 -2.05486)
			(size 0.3556 1.524)
			(layers "F.Cu" "F.Mask" "F.Paste")
			(net "TEMP_2_A1")
		)
		(pad "7" smd rect
			(at -0.32512 -2.05486)
			(size 0.3556 1.524)
			(layers "F.Cu" "F.Mask" "F.Paste")
			(net "TEMP_2_A0")
		)
		(pad "8" smd rect
			(at -0.97536 -2.05486)
			(size 0.3556 1.524)
			(layers "F.Cu" "F.Mask" "F.Paste")
			(net "P3V3_STBY")
		)
	)
	(footprint ""
		(layer "F.Cu")
		(at 155.499816 -153.999946)
		(property "Reference" ""
			(at 0 0 0)
			(layer "F.SilkS")
			(hide yes)
			(effects
				(font
					(size 1.27 1.27)
				)
			)
		)
		(property "Value" "*"
			(at -6.38175 0.19685 0)
			(unlocked yes)
			(layer "F.Fab")
			(hide yes)
			(effects
				(font
					(size 1.016 1.016)
					(thickness 0.1524)
				)
			)
		)
		(duplicate_pad_numbers_are_jumpers no)
		(fp_poly
			(pts
				(arc
					(start 5.0673 0)
					(mid -5.0673 0)
					(end 5.0673 0)
				)
			)
			(stroke
				(width 0)
				(type default)
			)
			(fill no)
			(layer "B.CrtYd")
		)
		(fp_poly
			(pts
				(arc
					(start 5.0673 0)
					(mid -5.0673 0)
					(end 5.0673 0)
				)
			)
			(stroke
				(width 0)
				(type default)
			)
			(fill no)
			(layer "F.CrtYd")
		)
		(fp_poly
			(pts
				(arc
					(start 5.0673 0)
					(mid -5.0673 0)
					(end 5.0673 0)
				)
			)
			(stroke
				(width 0)
				(type default)
			)
			(fill no)
			(layer "B.Fab")
		)
		(fp_poly
			(pts
				(arc
					(start 5.0673 0)
					(mid -5.0673 0)
					(end 5.0673 0)
				)
			)
			(stroke
				(width 0)
				(type default)
			)
			(fill no)
			(layer "F.Fab")
		)
		(pad "1" thru_hole circle
			(at 0 0)
			(size 9.525 9.525)
			(drill 3.5052)
			(layers "*.Cu" "*.Mask")
			(remove_unused_layers no)
			(net "Net_39")
			(clearance -2.5019)
			(thermal_gap 0.3048)
			(padstack
				(mode front_inner_back)
				(layer "Inner"
					(shape circle)
					(size 3.9116 3.9116)
					(clearance 0.3048)
				)
				(layer "B.Cu"
					(shape circle)
					(size 9.525 9.525)
					(clearance -2.5019)
				)
			)
		)
	)
	(footprint ""
		(layer "F.Cu")
		(at 98.676206 -140.77569 180)
		(property "Reference" "R423"
			(at 0 0 180)
			(layer "F.SilkS")
			(hide yes)
			(effects
				(font
					(size 1.27 1.27)
				)
			)
		)
		(property "Value" "4K7R2F-GP"
			(at 0.064008 -3.993896 180)
			(unlocked yes)
			(layer "F.Fab")
			(hide yes)
			(effects
				(font
					(size 1.016 1.016)
					(thickness 0.1524)
				)
			)
		)
		(property "Device Type" "R402H16"
			(at 0.064008 -5.517896 180)
			(unlocked yes)
			(layer "F.Fab")
			(hide yes)
			(effects
				(font
					(size 1.016 1.016)
					(thickness 0.1524)
				)
			)
		)
		(duplicate_pad_numbers_are_jumpers no)
		(fp_line
			(start 0.508 -0.9398)
			(end -0.508 -0.9398)
			(stroke
				(width 0.1524)
				(type default)
			)
			(layer "F.SilkS")
		)
		(fp_line
			(start -0.508 -0.9398)
			(end -0.508 0.9398)
			(stroke
				(width 0.1524)
				(type default)
			)
			(layer "F.SilkS")
		)
		(fp_rect
			(start -0.508 0.9398)
			(end 0.508 -0.9398)
			(stroke
				(width 0)
				(type default)
			)
			(fill no)
			(layer "F.CrtYd")
		)
		(fp_rect
			(start -0.508 0.9398)
			(end 0.508 -0.9398)
			(stroke
				(width 0)
				(type default)
			)
			(fill no)
			(layer "F.Fab")
		)
		(pad "1" smd custom
			(at 0 -0.4445 180)
			(size 0.1397 0.1397)
			(layers "F.Cu" "F.Mask" "F.Paste")
			(net "P3V3_STBY")
			(options
				(clearance outline)
				(anchor circle)
			)
			(primitives
				(gr_poly
					(pts
						(arc
							(start -0.1778 -0.2794)
							(mid -0.249642 -0.249642)
							(end -0.2794 -0.1778)
						)
						(arc
							(start -0.2794 0.1778)
							(mid -0.249642 0.249642)
							(end -0.1778 0.2794)
						)
						(arc
							(start 0.1778 0.2794)
							(mid 0.249642 0.249642)
							(end 0.2794 0.1778)
						)
						(arc
							(start 0.2794 -0.1778)
							(mid 0.249642 -0.249642)
							(end 0.1778 -0.2794)
						)
					)
					(width 0)
					(fill yes)
				)
			)
		)
		(pad "2" smd custom
			(at 0 0.4445 180)
			(size 0.1397 0.1397)
			(layers "F.Cu" "F.Mask" "F.Paste")
			(net "TCA9555_A0")
			(options
				(clearance outline)
				(anchor circle)
			)
			(primitives
				(gr_poly
					(pts
						(arc
							(start -0.1778 -0.2794)
							(mid -0.249642 -0.249642)
							(end -0.2794 -0.1778)
						)
						(arc
							(start -0.2794 0.1778)
							(mid -0.249642 0.249642)
							(end -0.1778 0.2794)
						)
						(arc
							(start 0.1778 0.2794)
							(mid 0.249642 0.249642)
							(end 0.2794 0.1778)
						)
						(arc
							(start 0.2794 -0.1778)
							(mid 0.249642 -0.249642)
							(end 0.1778 -0.2794)
						)
					)
					(width 0)
					(fill yes)
				)
			)
		)
	)
)
